(kicad_pcb
	(version 20260206)
	(generator "pcbnew")
	(generator_version "10.0")
	(general
		(thickness 1.6)
		(legacy_teardrops no)
	)
	(paper "A4")
	(title_block
		(title "9054_F0T_PDB_BD_GPU_F_V04_1213_1550_OCP.brd")
		(comment 1 "Grand Teton / footprints 137-143 of 608")
	)
	(layers
		(0 "F.Cu" signal "TOP")
		(4 "In1.Cu" signal "GND")
		(6 "In2.Cu" signal "IN1")
		(8 "In3.Cu" signal "GND1")
		(10 "In4.Cu" signal "VCC")
		(12 "In5.Cu" signal "VCC1")
		(14 "In6.Cu" signal "GND2")
		(16 "In7.Cu" signal "IN2")
		(18 "In8.Cu" signal "GND3")
		(2 "B.Cu" signal "BOTTOM")
		(9 "F.Adhes" user "F.Adhesive")
		(11 "B.Adhes" user "B.Adhesive")
		(13 "F.Paste" user "Package Geometry/Pastemask Top")
		(15 "B.Paste" user "Package Geometry/Pastemask Bottom")
		(5 "F.SilkS" user "Ref Des/Silkscreen Top")
		(7 "B.SilkS" user "Ref Des/Silkscreen Bottom")
		(1 "F.Mask" user "Board Geometry/Soldermask Top")
		(3 "B.Mask" user "Board Geometry/Soldermask Bottom")
		(17 "Dwgs.User" user "User.Drawings")
		(19 "Cmts.User" user "User.Comments")
		(21 "Eco1.User" user "User.Eco1")
		(23 "Eco2.User" user "User.Eco2")
		(25 "Edge.Cuts" user "Board Geometry/Outline")
		(27 "Margin" user)
		(31 "F.CrtYd" user "Package Geometry/Place Bound Top")
		(29 "B.CrtYd" user "Package Geometry/Place Bound Bottom")
		(35 "F.Fab" user "Ref Des/Assembly Top")
		(33 "B.Fab" user "Ref Des/Assembly Bottom")
	)
	(footprint ""
		(layer "F.Cu")
		(at 440.69 -48.768 90)
		(property "Reference" "U26"
			(at 1.8415 1.18237 90)
			(unlocked yes)
			(layer "F.SilkS")
			(effects
				(font
					(size 0.7874 0.5842)
					(thickness 0.1524)
				)
				(justify left)
			)
		)
		(property "Value" ""
			(at 0 0 90)
			(layer "F.Fab")
			(effects
				(font
					(size 1.27 1.27)
				)
			)
		)
		(duplicate_pad_numbers_are_jumpers no)
		(fp_line
			(start 1.603248 -1.500124)
			(end 1.603248 1.500124)
			(stroke
				(width 0.1524)
				(type default)
			)
			(layer "F.SilkS")
		)
		(fp_line
			(start -1.603248 -1.500124)
			(end 1.603248 -1.500124)
			(stroke
				(width 0.1524)
				(type default)
			)
			(layer "F.SilkS")
		)
		(fp_line
			(start 1.603248 1.500124)
			(end -1.603248 1.500124)
			(stroke
				(width 0.1524)
				(type default)
			)
			(layer "F.SilkS")
		)
		(fp_line
			(start -1.603248 1.500124)
			(end -1.603248 -1.500124)
			(stroke
				(width 0.1524)
				(type default)
			)
			(layer "F.SilkS")
		)
		(fp_line
			(start 0.700024 -1.500124)
			(end -0.700024 -1.500124)
			(stroke
				(width 0.1)
				(type default)
			)
			(layer "F.Fab")
		)
		(fp_line
			(start -0.700024 -1.500124)
			(end -0.700024 -1.169924)
			(stroke
				(width 0.1)
				(type default)
			)
			(layer "F.Fab")
		)
		(fp_line
			(start -0.700024 -1.169924)
			(end -1.249934 -1.169924)
			(stroke
				(width 0.1)
				(type default)
			)
			(layer "F.Fab")
		)
		(fp_line
			(start -1.249934 -1.169924)
			(end -1.249934 -0.729996)
			(stroke
				(width 0.1)
				(type default)
			)
			(layer "F.Fab")
		)
		(fp_line
			(start -0.6985 -0.729996)
			(end -0.6985 0.729996)
			(stroke
				(width 0.1)
				(type default)
			)
			(layer "F.Fab")
		)
		(fp_line
			(start -1.249934 -0.729996)
			(end -0.6985 -0.729996)
			(stroke
				(width 0.1)
				(type default)
			)
			(layer "F.Fab")
		)
		(fp_line
			(start 1.249934 -0.219964)
			(end 0.700024 -0.219964)
			(stroke
				(width 0.1)
				(type default)
			)
			(layer "F.Fab")
		)
		(fp_line
			(start 0.700024 -0.219964)
			(end 0.700024 -1.500124)
			(stroke
				(width 0.1)
				(type default)
			)
			(layer "F.Fab")
		)
		(fp_line
			(start 1.249934 0.219964)
			(end 1.249934 -0.219964)
			(stroke
				(width 0.1)
				(type default)
			)
			(layer "F.Fab")
		)
		(fp_line
			(start 0.700024 0.219964)
			(end 1.249934 0.219964)
			(stroke
				(width 0.1)
				(type default)
			)
			(layer "F.Fab")
		)
		(fp_line
			(start -0.6985 0.729996)
			(end -1.249934 0.729996)
			(stroke
				(width 0.1)
				(type default)
			)
			(layer "F.Fab")
		)
		(fp_line
			(start -1.249934 0.729996)
			(end -1.249934 1.169924)
			(stroke
				(width 0.1)
				(type default)
			)
			(layer "F.Fab")
		)
		(fp_line
			(start -0.700024 1.169924)
			(end -0.700024 1.500124)
			(stroke
				(width 0.1)
				(type default)
			)
			(layer "F.Fab")
		)
		(fp_line
			(start -1.249934 1.169924)
			(end -0.700024 1.169924)
			(stroke
				(width 0.1)
				(type default)
			)
			(layer "F.Fab")
		)
		(fp_line
			(start 0.700024 1.500124)
			(end 0.700024 0.219964)
			(stroke
				(width 0.1)
				(type default)
			)
			(layer "F.Fab")
		)
		(fp_line
			(start -0.700024 1.500124)
			(end 0.700024 1.500124)
			(stroke
				(width 0.1)
				(type default)
			)
			(layer "F.Fab")
		)
		(fp_rect
			(start -0.700024 1.500124)
			(end 0.700024 -1.500124)
			(stroke
				(width 0)
				(type default)
			)
			(fill no)
			(layer "F.Fab")
		)
		(pad "D" smd rect
			(at 0.999998 0)
			(size 0.8128 0.9144)
			(layers "F.Cu" "F.Mask" "F.Paste")
			(net "PWRGD_P3V3_AUX_MB_BUF_N")
		)
		(pad "G" smd rect
			(at -0.999998 -0.94996)
			(size 0.8128 0.9144)
			(layers "F.Cu" "F.Mask" "F.Paste")
			(net "PWRGD_P3V3_AUX_MB_BUF")
		)
		(pad "S" smd rect
			(at -0.999998 0.94996)
			(size 0.8128 0.9144)
			(layers "F.Cu" "F.Mask" "F.Paste")
			(net "GND")
		)
	)
	(footprint ""
		(layer "F.Cu")
		(at 42.36339 -58.42)
		(property "Reference" "PC46"
			(at 5.66801 -5.05333 0)
			(unlocked yes)
			(layer "F.SilkS")
			(effects
				(font
					(size 0.7874 0.5842)
					(thickness 0.1524)
				)
				(justify left)
			)
		)
		(property "Value" ""
			(at 0 0 0)
			(layer "F.Fab")
			(effects
				(font
					(size 1.27 1.27)
				)
			)
		)
		(duplicate_pad_numbers_are_jumpers no)
		(fp_line
			(start -9.253728 3.750056)
			(end 9.249918 3.750056)
			(stroke
				(width 0.1524)
				(type default)
			)
			(layer "F.SilkS")
		)
		(fp_line
			(start 0 3.750056)
			(end -9.253728 3.750056)
			(stroke
				(width 0.1524)
				(type default)
			)
			(layer "F.SilkS")
		)
		(fp_circle
			(center 0 3.750056)
			(end 9.249918 3.750056)
			(stroke
				(width 0.1524)
				(type default)
			)
			(fill no)
			(layer "F.SilkS")
		)
		(fp_poly
			(pts
				(arc
					(start 9.249918 3.750056)
					(mid 0 12.999974)
					(end -9.249918 3.750056)
				)
			)
			(stroke
				(width 0)
				(type default)
			)
			(fill yes)
			(layer "F.SilkS")
		)
		(fp_circle
			(center 0 3.750056)
			(end 9.249918 3.750056)
			(stroke
				(width 0.1)
				(type default)
			)
			(fill no)
			(layer "F.Fab")
		)
		(pad "1" thru_hole rect
			(at 0 0)
			(size 1.778 1.778)
			(drill 1.27)
			(layers "*.Cu" "*.Mask")
			(remove_unused_layers no)
			(net "P52V_HS2")
			(clearance 0)
			(padstack
				(mode front_inner_back)
				(layer "Inner"
					(shape circle)
					(size 1.778 1.778)
					(clearance 0)
				)
				(layer "B.Cu"
					(shape rect)
					(size 1.778 1.778)
					(clearance 0)
				)
			)
		)
		(pad "2" thru_hole circle
			(at 0 7.500112)
			(size 1.778 1.778)
			(drill 1.27)
			(layers "*.Cu" "*.Mask")
			(remove_unused_layers no)
			(net "GND")
			(clearance 0)
		)
	)
	(footprint ""
		(layer "F.Cu")
		(at 412.73476 -27.852878 90)
		(property "Reference" "R5919"
			(at 0 0 90)
			(layer "F.SilkS")
			(hide yes)
			(effects
				(font
					(size 1.27 1.27)
				)
			)
		)
		(property "Value" ""
			(at 0 0 90)
			(layer "F.Fab")
			(effects
				(font
					(size 1.27 1.27)
				)
			)
		)
		(duplicate_pad_numbers_are_jumpers no)
		(fp_line
			(start 0.7874 -0.4064)
			(end 0.7874 0.4064)
			(stroke
				(width 0.1524)
				(type default)
			)
			(layer "F.SilkS")
		)
		(fp_line
			(start -0.7874 -0.4064)
			(end 0.7874 -0.4064)
			(stroke
				(width 0.1524)
				(type default)
			)
			(layer "F.SilkS")
		)
		(fp_line
			(start 0.7874 0.4064)
			(end -0.7874 0.4064)
			(stroke
				(width 0.1524)
				(type default)
			)
			(layer "F.SilkS")
		)
		(fp_line
			(start -0.7874 0.4064)
			(end -0.7874 -0.4064)
			(stroke
				(width 0.1524)
				(type default)
			)
			(layer "F.SilkS")
		)
		(fp_line
			(start -0.12065 -0.305054)
			(end -0.12065 -0.2794)
			(stroke
				(width 0.1)
				(type default)
			)
			(layer "F.Fab")
		)
		(fp_line
			(start -0.67945 -0.305054)
			(end -0.12065 -0.305054)
			(stroke
				(width 0.1)
				(type default)
			)
			(layer "F.Fab")
		)
		(fp_line
			(start 0.67945 -0.3048)
			(end 0.67945 0.3048)
			(stroke
				(width 0.1)
				(type default)
			)
			(layer "F.Fab")
		)
		(fp_line
			(start 0.12065 -0.3048)
			(end 0.67945 -0.3048)
			(stroke
				(width 0.1)
				(type default)
			)
			(layer "F.Fab")
		)
		(fp_line
			(start 0.12065 -0.2794)
			(end 0.12065 -0.3048)
			(stroke
				(width 0.1)
				(type default)
			)
			(layer "F.Fab")
		)
		(fp_line
			(start -0.12065 -0.2794)
			(end 0.12065 -0.2794)
			(stroke
				(width 0.1)
				(type default)
			)
			(layer "F.Fab")
		)
		(fp_line
			(start 0.120396 0.2794)
			(end -0.12065 0.2794)
			(stroke
				(width 0.1)
				(type default)
			)
			(layer "F.Fab")
		)
		(fp_line
			(start -0.12065 0.2794)
			(end -0.12065 0.3048)
			(stroke
				(width 0.1)
				(type default)
			)
			(layer "F.Fab")
		)
		(fp_line
			(start 0.67945 0.3048)
			(end 0.120396 0.3048)
			(stroke
				(width 0.1)
				(type default)
			)
			(layer "F.Fab")
		)
		(fp_line
			(start 0.120396 0.3048)
			(end 0.120396 0.2794)
			(stroke
				(width 0.1)
				(type default)
			)
			(layer "F.Fab")
		)
		(fp_line
			(start -0.12065 0.3048)
			(end -0.67945 0.3048)
			(stroke
				(width 0.1)
				(type default)
			)
			(layer "F.Fab")
		)
		(fp_line
			(start -0.67945 0.3048)
			(end -0.67945 -0.305054)
			(stroke
				(width 0.1)
				(type default)
			)
			(layer "F.Fab")
		)
		(pad "1" smd rect
			(at -0.40005 0 270)
			(size 0.4572 0.508)
			(layers "F.Cu" "F.Mask" "F.Paste")
			(net "P12V_HPDB")
		)
		(pad "2" smd rect
			(at 0.40005 0 270)
			(size 0.4572 0.508)
			(layers "F.Cu" "F.Mask" "F.Paste")
			(net "P12V_LED_FB")
		)
	)
	(footprint ""
		(layer "F.Cu")
		(at 172.847 -84.709 90)
		(property "Reference" "C93"
			(at 0 0 90)
			(layer "F.SilkS")
			(hide yes)
			(effects
				(font
					(size 1.27 1.27)
				)
			)
		)
		(property "Value" ""
			(at 0 0 90)
			(layer "F.Fab")
			(effects
				(font
					(size 1.27 1.27)
				)
			)
		)
		(duplicate_pad_numbers_are_jumpers no)
		(fp_line
			(start 0.7874 -0.4064)
			(end 0.7874 0.4064)
			(stroke
				(width 0.1524)
				(type default)
			)
			(layer "F.SilkS")
		)
		(fp_line
			(start -0.7874 -0.4064)
			(end 0.7874 -0.4064)
			(stroke
				(width 0.1524)
				(type default)
			)
			(layer "F.SilkS")
		)
		(fp_line
			(start 0.7874 0.4064)
			(end -0.7874 0.4064)
			(stroke
				(width 0.1524)
				(type default)
			)
			(layer "F.SilkS")
		)
		(fp_line
			(start -0.7874 0.4064)
			(end -0.7874 -0.4064)
			(stroke
				(width 0.1524)
				(type default)
			)
			(layer "F.SilkS")
		)
		(fp_line
			(start -0.12065 -0.305054)
			(end -0.12065 -0.2794)
			(stroke
				(width 0.1)
				(type default)
			)
			(layer "F.Fab")
		)
		(fp_line
			(start -0.67945 -0.305054)
			(end -0.12065 -0.305054)
			(stroke
				(width 0.1)
				(type default)
			)
			(layer "F.Fab")
		)
		(fp_line
			(start 0.67945 -0.3048)
			(end 0.67945 0.3048)
			(stroke
				(width 0.1)
				(type default)
			)
			(layer "F.Fab")
		)
		(fp_line
			(start 0.12065 -0.3048)
			(end 0.67945 -0.3048)
			(stroke
				(width 0.1)
				(type default)
			)
			(layer "F.Fab")
		)
		(fp_line
			(start 0.12065 -0.2794)
			(end 0.12065 -0.3048)
			(stroke
				(width 0.1)
				(type default)
			)
			(layer "F.Fab")
		)
		(fp_line
			(start -0.12065 -0.2794)
			(end 0.12065 -0.2794)
			(stroke
				(width 0.1)
				(type default)
			)
			(layer "F.Fab")
		)
		(fp_line
			(start 0.120396 0.2794)
			(end -0.12065 0.2794)
			(stroke
				(width 0.1)
				(type default)
			)
			(layer "F.Fab")
		)
		(fp_line
			(start -0.12065 0.2794)
			(end -0.12065 0.3048)
			(stroke
				(width 0.1)
				(type default)
			)
			(layer "F.Fab")
		)
		(fp_line
			(start 0.67945 0.3048)
			(end 0.120396 0.3048)
			(stroke
				(width 0.1)
				(type default)
			)
			(layer "F.Fab")
		)
		(fp_line
			(start 0.120396 0.3048)
			(end 0.120396 0.2794)
			(stroke
				(width 0.1)
				(type default)
			)
			(layer "F.Fab")
		)
		(fp_line
			(start -0.12065 0.3048)
			(end -0.67945 0.3048)
			(stroke
				(width 0.1)
				(type default)
			)
			(layer "F.Fab")
		)
		(fp_line
			(start -0.67945 0.3048)
			(end -0.67945 -0.305054)
			(stroke
				(width 0.1)
				(type default)
			)
			(layer "F.Fab")
		)
		(pad "1" smd circle
			(at -0.40005 0 90)
			(size 0 0)
			(layers "F.Cu" "F.Mask" "F.Paste")
			(net "P3V3_2_AND")
		)
		(pad "2" smd circle
			(at 0.40005 0 90)
			(size 0 0)
			(layers "F.Cu" "F.Mask" "F.Paste")
			(net "GND")
		)
	)
	(footprint ""
		(layer "F.Cu")
		(at 176.1744 -64.897)
		(property "Reference" "PR6980"
			(at 0 0 0)
			(layer "F.SilkS")
			(hide yes)
			(effects
				(font
					(size 1.27 1.27)
				)
			)
		)
		(property "Value" ""
			(at 0 0 0)
			(layer "F.Fab")
			(effects
				(font
					(size 1.27 1.27)
				)
			)
		)
		(duplicate_pad_numbers_are_jumpers no)
		(fp_line
			(start -0.7874 -0.4064)
			(end 0.7874 -0.4064)
			(stroke
				(width 0.1524)
				(type default)
			)
			(layer "F.SilkS")
		)
		(fp_line
			(start -0.7874 0.4064)
			(end -0.7874 -0.4064)
			(stroke
				(width 0.1524)
				(type default)
			)
			(layer "F.SilkS")
		)
		(fp_line
			(start 0.7874 -0.4064)
			(end 0.7874 0.4064)
			(stroke
				(width 0.1524)
				(type default)
			)
			(layer "F.SilkS")
		)
		(fp_line
			(start 0.7874 0.4064)
			(end -0.7874 0.4064)
			(stroke
				(width 0.1524)
				(type default)
			)
			(layer "F.SilkS")
		)
		(fp_line
			(start -0.67945 -0.305054)
			(end -0.12065 -0.305054)
			(stroke
				(width 0.1)
				(type default)
			)
			(layer "F.Fab")
		)
		(fp_line
			(start -0.67945 0.3048)
			(end -0.67945 -0.305054)
			(stroke
				(width 0.1)
				(type default)
			)
			(layer "F.Fab")
		)
		(fp_line
			(start -0.12065 -0.305054)
			(end -0.12065 -0.2794)
			(stroke
				(width 0.1)
				(type default)
			)
			(layer "F.Fab")
		)
		(fp_line
			(start -0.12065 -0.2794)
			(end 0.12065 -0.2794)
			(stroke
				(width 0.1)
				(type default)
			)
			(layer "F.Fab")
		)
		(fp_line
			(start -0.12065 0.2794)
			(end -0.12065 0.3048)
			(stroke
				(width 0.1)
				(type default)
			)
			(layer "F.Fab")
		)
		(fp_line
			(start -0.12065 0.3048)
			(end -0.67945 0.3048)
			(stroke
				(width 0.1)
				(type default)
			)
			(layer "F.Fab")
		)
		(fp_line
			(start 0.120396 0.2794)
			(end -0.12065 0.2794)
			(stroke
				(width 0.1)
				(type default)
			)
			(layer "F.Fab")
		)
		(fp_line
			(start 0.120396 0.3048)
			(end 0.120396 0.2794)
			(stroke
				(width 0.1)
				(type default)
			)
			(layer "F.Fab")
		)
		(fp_line
			(start 0.12065 -0.3048)
			(end 0.67945 -0.3048)
			(stroke
				(width 0.1)
				(type default)
			)
			(layer "F.Fab")
		)
		(fp_line
			(start 0.12065 -0.2794)
			(end 0.12065 -0.3048)
			(stroke
				(width 0.1)
				(type default)
			)
			(layer "F.Fab")
		)
		(fp_line
			(start 0.67945 -0.3048)
			(end 0.67945 0.3048)
			(stroke
				(width 0.1)
				(type default)
			)
			(layer "F.Fab")
		)
		(fp_line
			(start 0.67945 0.3048)
			(end 0.120396 0.3048)
			(stroke
				(width 0.1)
				(type default)
			)
			(layer "F.Fab")
		)
		(pad "1" smd circle
			(at -0.40005 0)
			(size 0 0)
			(layers "F.Cu" "F.Mask" "F.Paste")
			(net "P52V_HS2_UVLO_EN")
		)
		(pad "2" smd circle
			(at 0.40005 0)
			(size 0 0)
			(layers "F.Cu" "F.Mask" "F.Paste")
			(net "GND1_FIELD_SIGNAL")
		)
	)
	(footprint ""
		(layer "F.Cu")
		(at 48.9204 -34.671 -90)
		(property "Reference" "PR104"
			(at 0 0 270)
			(layer "F.SilkS")
			(hide yes)
			(effects
				(font
					(size 1.27 1.27)
				)
			)
		)
		(property "Value" ""
			(at 0 0 270)
			(layer "F.Fab")
			(effects
				(font
					(size 1.27 1.27)
				)
			)
		)
		(duplicate_pad_numbers_are_jumpers no)
		(fp_line
			(start -2.234946 0.9271)
			(end -2.234946 -0.9271)
			(stroke
				(width 0.1524)
				(type default)
			)
			(layer "F.SilkS")
		)
		(fp_line
			(start 2.234946 0.9271)
			(end -2.234946 0.9271)
			(stroke
				(width 0.1524)
				(type default)
			)
			(layer "F.SilkS")
		)
		(fp_line
			(start -2.234946 -0.9271)
			(end 2.234946 -0.9271)
			(stroke
				(width 0.1524)
				(type default)
			)
			(layer "F.SilkS")
		)
		(fp_line
			(start 2.234946 -0.9271)
			(end 2.234946 0.9271)
			(stroke
				(width 0.1524)
				(type default)
			)
			(layer "F.SilkS")
		)
		(fp_line
			(start -1.575054 0.824992)
			(end 1.575054 0.824992)
			(stroke
				(width 0.1)
				(type default)
			)
			(layer "F.Fab")
		)
		(fp_line
			(start 1.575054 0.824992)
			(end 1.575054 -0.824992)
			(stroke
				(width 0.1)
				(type default)
			)
			(layer "F.Fab")
		)
		(fp_line
			(start -1.575054 -0.824992)
			(end -1.575054 0.824992)
			(stroke
				(width 0.1)
				(type default)
			)
			(layer "F.Fab")
		)
		(fp_line
			(start 1.575054 -0.824992)
			(end -1.575054 -0.824992)
			(stroke
				(width 0.1)
				(type default)
			)
			(layer "F.Fab")
		)
		(pad "1" smd rect
			(at -1.599946 0 270)
			(size 1.016 1.6002)
			(layers "F.Cu" "F.Mask" "F.Paste")
			(net "P52V_HS2")
		)
		(pad "2" smd rect
			(at 1.599946 0 270)
			(size 1.016 1.6002)
			(layers "F.Cu" "F.Mask" "F.Paste")
			(net "P52V_HS2_EN_DISCHARGE_N")
		)
	)
	(footprint ""
		(layer "F.Cu")
		(at 169.751756 -144.790668 -90)
		(property "Reference" "J12"
			(at 3.185668 -5.661914 90)
			(unlocked yes)
			(layer "F.SilkS")
			(effects
				(font
					(size 0.7874 0.5842)
					(thickness 0.1524)
				)
				(justify left)
			)
		)
		(property "Value" ""
			(at 0 0 270)
			(layer "F.Fab")
			(effects
				(font
					(size 1.27 1.27)
				)
			)
		)
		(duplicate_pad_numbers_are_jumpers no)
		(fp_line
			(start 0 4.011168)
			(end -3.330702 -4.771136)
			(stroke
				(width 0.1524)
				(type default)
			)
			(layer "F.SilkS")
		)
		(fp_line
			(start -3.330702 -4.771136)
			(end 3.330702 -4.771136)
			(stroke
				(width 0.1524)
				(type default)
			)
			(layer "F.SilkS")
		)
		(fp_line
			(start 3.330702 -4.771136)
			(end 0 4.011168)
			(stroke
				(width 0.1524)
				(type default)
			)
			(layer "F.SilkS")
		)
		(fp_line
			(start 0 4.011168)
			(end -3.330702 -4.771136)
			(stroke
				(width 0.1)
				(type default)
			)
			(layer "F.Fab")
		)
		(fp_line
			(start -3.330702 -4.771136)
			(end 3.330702 -4.771136)
			(stroke
				(width 0.1)
				(type default)
			)
			(layer "F.Fab")
		)
		(fp_line
			(start 3.330702 -4.771136)
			(end 0 4.011168)
			(stroke
				(width 0.1)
				(type default)
			)
			(layer "F.Fab")
		)
		(pad "1" thru_hole circle
			(at 0 0 270)
			(size 2.159 2.159)
			(drill 1.7018)
			(layers "*.Cu" "*.Mask")
			(remove_unused_layers no)
			(net "GND3")
			(clearance 0.0254)
			(thermal_gap 0.0254)
		)
		(pad "2" thru_hole circle
			(at -1.27 -3.348736 270)
			(size 2.159 2.159)
			(drill 1.7018)
			(layers "*.Cu" "*.Mask")
			(remove_unused_layers no)
			(net "TDR_SE_50_OHM_IN1")
			(clearance 0.0254)
			(thermal_gap 0.0254)
		)
		(pad "3" thru_hole circle
			(at 1.27 -3.348736 270)
			(size 2.159 2.159)
			(drill 1.7018)
			(layers "*.Cu" "*.Mask")
			(remove_unused_layers no)
			(net "TDR_SE_50_OHM_IN1")
			(clearance 0.0254)
			(thermal_gap 0.0254)
		)
	)
)
